(kicad_pcb
	(version 20260206)
	(generator "pcbnew")
	(generator_version "10.0")
	(general
		(thickness 1.6)
		(legacy_teardrops no)
	)
	(paper "A4")
	(title_block
		(title "03242023_DA0F0TMBIJ0_F0T_Motherboard_J_brd_V01_OCP.brd")
		(comment 1 "Grand Teton / footprints 1917-1922 of 6105")
	)
	(layers
		(0 "F.Cu" signal "TOP")
		(4 "In1.Cu" signal "GND")
		(6 "In2.Cu" signal "IN1")
		(8 "In3.Cu" signal "GND1")
		(10 "In4.Cu" signal "IN2")
		(12 "In5.Cu" signal "GND2")
		(14 "In6.Cu" signal "IN3")
		(16 "In7.Cu" signal "GND3")
		(18 "In8.Cu" signal "VCC")
		(20 "In9.Cu" signal "VCC1")
		(22 "In10.Cu" signal "GND4")
		(24 "In11.Cu" signal "IN4")
		(26 "In12.Cu" signal "GND5")
		(28 "In13.Cu" signal "IN5")
		(30 "In14.Cu" signal "GND6")
		(32 "In15.Cu" signal "IN6")
		(34 "In16.Cu" signal "GND7")
		(2 "B.Cu" signal "BOTTOM")
		(9 "F.Adhes" user "F.Adhesive")
		(11 "B.Adhes" user "B.Adhesive")
		(13 "F.Paste" user "Package Geometry/Pastemask Top")
		(15 "B.Paste" user "Package Geometry/Pastemask Bottom")
		(5 "F.SilkS" user "Ref Des/Silkscreen Top")
		(7 "B.SilkS" user "Ref Des/Silkscreen Bottom")
		(1 "F.Mask" user "Board Geometry/Soldermask Top")
		(3 "B.Mask" user "Board Geometry/Soldermask Bottom")
		(17 "Dwgs.User" user "User.Drawings")
		(19 "Cmts.User" user "User.Comments")
		(21 "Eco1.User" user "User.Eco1")
		(23 "Eco2.User" user "User.Eco2")
		(25 "Edge.Cuts" user "Board Geometry/Outline")
		(27 "Margin" user)
		(31 "F.CrtYd" user "Package Geometry/Place Bound Top")
		(29 "B.CrtYd" user "Package Geometry/Place Bound Bottom")
		(35 "F.Fab" user "Ref Des/Assembly Top")
		(33 "B.Fab" user "Ref Des/Assembly Bottom")
	)
	(footprint ""
		(layer "F.Cu")
		(at 184.96788 -99.659948 -90)
		(property "Reference" "R130"
			(at 0 0 270)
			(layer "F.SilkS")
			(hide yes)
			(effects
				(font
					(size 1.27 1.27)
				)
			)
		)
		(property "Value" ""
			(at 0 0 270)
			(layer "F.Fab")
			(effects
				(font
					(size 1.27 1.27)
				)
			)
		)
		(duplicate_pad_numbers_are_jumpers no)
		(fp_line
			(start -0.7874 0.4064)
			(end -0.7874 -0.4064)
			(stroke
				(width 0.1524)
				(type default)
			)
			(layer "F.SilkS")
		)
		(fp_line
			(start 0.7874 0.4064)
			(end -0.7874 0.4064)
			(stroke
				(width 0.1524)
				(type default)
			)
			(layer "F.SilkS")
		)
		(fp_line
			(start -0.7874 -0.4064)
			(end 0.7874 -0.4064)
			(stroke
				(width 0.1524)
				(type default)
			)
			(layer "F.SilkS")
		)
		(fp_line
			(start 0.7874 -0.4064)
			(end 0.7874 0.4064)
			(stroke
				(width 0.1524)
				(type default)
			)
			(layer "F.SilkS")
		)
		(fp_line
			(start -0.67945 0.3048)
			(end -0.67945 -0.305054)
			(stroke
				(width 0.1)
				(type default)
			)
			(layer "F.Fab")
		)
		(fp_line
			(start -0.12065 0.3048)
			(end -0.67945 0.3048)
			(stroke
				(width 0.1)
				(type default)
			)
			(layer "F.Fab")
		)
		(fp_line
			(start 0.120396 0.3048)
			(end 0.120396 0.2794)
			(stroke
				(width 0.1)
				(type default)
			)
			(layer "F.Fab")
		)
		(fp_line
			(start 0.67945 0.3048)
			(end 0.120396 0.3048)
			(stroke
				(width 0.1)
				(type default)
			)
			(layer "F.Fab")
		)
		(fp_line
			(start -0.12065 0.2794)
			(end -0.12065 0.3048)
			(stroke
				(width 0.1)
				(type default)
			)
			(layer "F.Fab")
		)
		(fp_line
			(start 0.120396 0.2794)
			(end -0.12065 0.2794)
			(stroke
				(width 0.1)
				(type default)
			)
			(layer "F.Fab")
		)
		(fp_line
			(start -0.12065 -0.2794)
			(end 0.12065 -0.2794)
			(stroke
				(width 0.1)
				(type default)
			)
			(layer "F.Fab")
		)
		(fp_line
			(start 0.12065 -0.2794)
			(end 0.12065 -0.3048)
			(stroke
				(width 0.1)
				(type default)
			)
			(layer "F.Fab")
		)
		(fp_line
			(start 0.12065 -0.3048)
			(end 0.67945 -0.3048)
			(stroke
				(width 0.1)
				(type default)
			)
			(layer "F.Fab")
		)
		(fp_line
			(start 0.67945 -0.3048)
			(end 0.67945 0.3048)
			(stroke
				(width 0.1)
				(type default)
			)
			(layer "F.Fab")
		)
		(fp_line
			(start -0.67945 -0.305054)
			(end -0.12065 -0.305054)
			(stroke
				(width 0.1)
				(type default)
			)
			(layer "F.Fab")
		)
		(fp_line
			(start -0.12065 -0.305054)
			(end -0.12065 -0.2794)
			(stroke
				(width 0.1)
				(type default)
			)
			(layer "F.Fab")
		)
		(pad "1" smd circle
			(at -0.40005 0 270)
			(size 0 0)
			(layers "F.Cu" "F.Mask" "F.Paste")
			(net "PWRGD_CPU1_LVC1_R")
		)
		(pad "2" smd circle
			(at 0.40005 0 270)
			(size 0 0)
			(layers "F.Cu" "F.Mask" "F.Paste")
			(net "PWRGD_CPU1_BUF_R")
		)
	)
	(footprint ""
		(layer "F.Cu")
		(at 185.928762 -25.899872 180)
		(property "Reference" "PR4004"
			(at 0 0 180)
			(layer "F.SilkS")
			(hide yes)
			(effects
				(font
					(size 1.27 1.27)
				)
			)
		)
		(property "Value" ""
			(at 0 0 180)
			(layer "F.Fab")
			(effects
				(font
					(size 1.27 1.27)
				)
			)
		)
		(duplicate_pad_numbers_are_jumpers no)
		(fp_line
			(start 0.7874 0.4064)
			(end -0.7874 0.4064)
			(stroke
				(width 0.1524)
				(type default)
			)
			(layer "F.SilkS")
		)
		(fp_line
			(start 0.7874 -0.4064)
			(end 0.7874 0.4064)
			(stroke
				(width 0.1524)
				(type default)
			)
			(layer "F.SilkS")
		)
		(fp_line
			(start -0.7874 0.4064)
			(end -0.7874 -0.4064)
			(stroke
				(width 0.1524)
				(type default)
			)
			(layer "F.SilkS")
		)
		(fp_line
			(start -0.7874 -0.4064)
			(end 0.7874 -0.4064)
			(stroke
				(width 0.1524)
				(type default)
			)
			(layer "F.SilkS")
		)
		(fp_line
			(start 0.67945 0.3048)
			(end 0.120396 0.3048)
			(stroke
				(width 0.1)
				(type default)
			)
			(layer "F.Fab")
		)
		(fp_line
			(start 0.67945 -0.3048)
			(end 0.67945 0.3048)
			(stroke
				(width 0.1)
				(type default)
			)
			(layer "F.Fab")
		)
		(fp_line
			(start 0.12065 -0.2794)
			(end 0.12065 -0.3048)
			(stroke
				(width 0.1)
				(type default)
			)
			(layer "F.Fab")
		)
		(fp_line
			(start 0.12065 -0.3048)
			(end 0.67945 -0.3048)
			(stroke
				(width 0.1)
				(type default)
			)
			(layer "F.Fab")
		)
		(fp_line
			(start 0.120396 0.3048)
			(end 0.120396 0.2794)
			(stroke
				(width 0.1)
				(type default)
			)
			(layer "F.Fab")
		)
		(fp_line
			(start 0.120396 0.2794)
			(end -0.12065 0.2794)
			(stroke
				(width 0.1)
				(type default)
			)
			(layer "F.Fab")
		)
		(fp_line
			(start -0.12065 0.3048)
			(end -0.67945 0.3048)
			(stroke
				(width 0.1)
				(type default)
			)
			(layer "F.Fab")
		)
		(fp_line
			(start -0.12065 0.2794)
			(end -0.12065 0.3048)
			(stroke
				(width 0.1)
				(type default)
			)
			(layer "F.Fab")
		)
		(fp_line
			(start -0.12065 -0.2794)
			(end 0.12065 -0.2794)
			(stroke
				(width 0.1)
				(type default)
			)
			(layer "F.Fab")
		)
		(fp_line
			(start -0.12065 -0.305054)
			(end -0.12065 -0.2794)
			(stroke
				(width 0.1)
				(type default)
			)
			(layer "F.Fab")
		)
		(fp_line
			(start -0.67945 0.3048)
			(end -0.67945 -0.305054)
			(stroke
				(width 0.1)
				(type default)
			)
			(layer "F.Fab")
		)
		(fp_line
			(start -0.67945 -0.305054)
			(end -0.12065 -0.305054)
			(stroke
				(width 0.1)
				(type default)
			)
			(layer "F.Fab")
		)
		(pad "1" smd circle
			(at -0.40005 0 180)
			(size 0 0)
			(layers "F.Cu" "F.Mask" "F.Paste")
			(net "P12V_SCM_CB")
		)
		(pad "2" smd circle
			(at 0.40005 0 180)
			(size 0 0)
			(layers "F.Cu" "F.Mask" "F.Paste")
			(net "GND")
		)
	)
	(footprint ""
		(layer "F.Cu")
		(at 160.83788 -117.566948)
		(property "Reference" "R3249"
			(at 0 0 0)
			(layer "F.SilkS")
			(hide yes)
			(effects
				(font
					(size 1.27 1.27)
				)
			)
		)
		(property "Value" ""
			(at 0 0 0)
			(layer "F.Fab")
			(effects
				(font
					(size 1.27 1.27)
				)
			)
		)
		(duplicate_pad_numbers_are_jumpers no)
		(fp_line
			(start -0.7874 -0.4064)
			(end 0.7874 -0.4064)
			(stroke
				(width 0.1524)
				(type default)
			)
			(layer "F.SilkS")
		)
		(fp_line
			(start -0.7874 0.4064)
			(end -0.7874 -0.4064)
			(stroke
				(width 0.1524)
				(type default)
			)
			(layer "F.SilkS")
		)
		(fp_line
			(start 0.7874 -0.4064)
			(end 0.7874 0.4064)
			(stroke
				(width 0.1524)
				(type default)
			)
			(layer "F.SilkS")
		)
		(fp_line
			(start 0.7874 0.4064)
			(end -0.7874 0.4064)
			(stroke
				(width 0.1524)
				(type default)
			)
			(layer "F.SilkS")
		)
		(fp_line
			(start -0.67945 -0.305054)
			(end -0.12065 -0.305054)
			(stroke
				(width 0.1)
				(type default)
			)
			(layer "F.Fab")
		)
		(fp_line
			(start -0.67945 0.3048)
			(end -0.67945 -0.305054)
			(stroke
				(width 0.1)
				(type default)
			)
			(layer "F.Fab")
		)
		(fp_line
			(start -0.12065 -0.305054)
			(end -0.12065 -0.2794)
			(stroke
				(width 0.1)
				(type default)
			)
			(layer "F.Fab")
		)
		(fp_line
			(start -0.12065 -0.2794)
			(end 0.12065 -0.2794)
			(stroke
				(width 0.1)
				(type default)
			)
			(layer "F.Fab")
		)
		(fp_line
			(start -0.12065 0.2794)
			(end -0.12065 0.3048)
			(stroke
				(width 0.1)
				(type default)
			)
			(layer "F.Fab")
		)
		(fp_line
			(start -0.12065 0.3048)
			(end -0.67945 0.3048)
			(stroke
				(width 0.1)
				(type default)
			)
			(layer "F.Fab")
		)
		(fp_line
			(start 0.120396 0.2794)
			(end -0.12065 0.2794)
			(stroke
				(width 0.1)
				(type default)
			)
			(layer "F.Fab")
		)
		(fp_line
			(start 0.120396 0.3048)
			(end 0.120396 0.2794)
			(stroke
				(width 0.1)
				(type default)
			)
			(layer "F.Fab")
		)
		(fp_line
			(start 0.12065 -0.3048)
			(end 0.67945 -0.3048)
			(stroke
				(width 0.1)
				(type default)
			)
			(layer "F.Fab")
		)
		(fp_line
			(start 0.12065 -0.2794)
			(end 0.12065 -0.3048)
			(stroke
				(width 0.1)
				(type default)
			)
			(layer "F.Fab")
		)
		(fp_line
			(start 0.67945 -0.3048)
			(end 0.67945 0.3048)
			(stroke
				(width 0.1)
				(type default)
			)
			(layer "F.Fab")
		)
		(fp_line
			(start 0.67945 0.3048)
			(end 0.120396 0.3048)
			(stroke
				(width 0.1)
				(type default)
			)
			(layer "F.Fab")
		)
		(pad "1" smd circle
			(at -0.40005 0)
			(size 0 0)
			(layers "F.Cu" "F.Mask" "F.Paste")
			(net "P3V3_AUX")
		)
		(pad "2" smd circle
			(at 0.40005 0)
			(size 0 0)
			(layers "F.Cu" "F.Mask" "F.Paste")
			(net "PU_FPGA_D12_PROGRAMN")
		)
	)
	(footprint ""
		(layer "F.Cu")
		(at 297.152314 -14.506194 180)
		(property "Reference" "R4188"
			(at 0 0 180)
			(layer "F.SilkS")
			(hide yes)
			(effects
				(font
					(size 1.27 1.27)
				)
			)
		)
		(property "Value" ""
			(at 0 0 180)
			(layer "F.Fab")
			(effects
				(font
					(size 1.27 1.27)
				)
			)
		)
		(duplicate_pad_numbers_are_jumpers no)
		(fp_line
			(start 0.7874 0.4064)
			(end -0.7874 0.4064)
			(stroke
				(width 0.1524)
				(type default)
			)
			(layer "F.SilkS")
		)
		(fp_line
			(start 0.7874 -0.4064)
			(end 0.7874 0.4064)
			(stroke
				(width 0.1524)
				(type default)
			)
			(layer "F.SilkS")
		)
		(fp_line
			(start -0.7874 0.4064)
			(end -0.7874 -0.4064)
			(stroke
				(width 0.1524)
				(type default)
			)
			(layer "F.SilkS")
		)
		(fp_line
			(start -0.7874 -0.4064)
			(end 0.7874 -0.4064)
			(stroke
				(width 0.1524)
				(type default)
			)
			(layer "F.SilkS")
		)
		(fp_line
			(start 0.67945 0.3048)
			(end 0.120396 0.3048)
			(stroke
				(width 0.1)
				(type default)
			)
			(layer "F.Fab")
		)
		(fp_line
			(start 0.67945 -0.3048)
			(end 0.67945 0.3048)
			(stroke
				(width 0.1)
				(type default)
			)
			(layer "F.Fab")
		)
		(fp_line
			(start 0.12065 -0.2794)
			(end 0.12065 -0.3048)
			(stroke
				(width 0.1)
				(type default)
			)
			(layer "F.Fab")
		)
		(fp_line
			(start 0.12065 -0.3048)
			(end 0.67945 -0.3048)
			(stroke
				(width 0.1)
				(type default)
			)
			(layer "F.Fab")
		)
		(fp_line
			(start 0.120396 0.3048)
			(end 0.120396 0.2794)
			(stroke
				(width 0.1)
				(type default)
			)
			(layer "F.Fab")
		)
		(fp_line
			(start 0.120396 0.2794)
			(end -0.12065 0.2794)
			(stroke
				(width 0.1)
				(type default)
			)
			(layer "F.Fab")
		)
		(fp_line
			(start -0.12065 0.3048)
			(end -0.67945 0.3048)
			(stroke
				(width 0.1)
				(type default)
			)
			(layer "F.Fab")
		)
		(fp_line
			(start -0.12065 0.2794)
			(end -0.12065 0.3048)
			(stroke
				(width 0.1)
				(type default)
			)
			(layer "F.Fab")
		)
		(fp_line
			(start -0.12065 -0.2794)
			(end 0.12065 -0.2794)
			(stroke
				(width 0.1)
				(type default)
			)
			(layer "F.Fab")
		)
		(fp_line
			(start -0.12065 -0.305054)
			(end -0.12065 -0.2794)
			(stroke
				(width 0.1)
				(type default)
			)
			(layer "F.Fab")
		)
		(fp_line
			(start -0.67945 0.3048)
			(end -0.67945 -0.305054)
			(stroke
				(width 0.1)
				(type default)
			)
			(layer "F.Fab")
		)
		(fp_line
			(start -0.67945 -0.305054)
			(end -0.12065 -0.305054)
			(stroke
				(width 0.1)
				(type default)
			)
			(layer "F.Fab")
		)
		(pad "1" smd circle
			(at -0.40005 0 180)
			(size 0 0)
			(layers "F.Cu" "F.Mask" "F.Paste")
			(net "P3V3_AUX")
		)
		(pad "2" smd circle
			(at 0.40005 0 180)
			(size 0 0)
			(layers "F.Cu" "F.Mask" "F.Paste")
			(net "U271_1_ADD2")
		)
	)
	(footprint ""
		(layer "F.Cu")
		(at 248.845832 -39.21379 -90)
		(property "Reference" "C1277"
			(at 0 0 270)
			(layer "F.SilkS")
			(hide yes)
			(effects
				(font
					(size 1.27 1.27)
				)
			)
		)
		(property "Value" ""
			(at 0 0 270)
			(layer "F.Fab")
			(effects
				(font
					(size 1.27 1.27)
				)
			)
		)
		(duplicate_pad_numbers_are_jumpers no)
		(fp_line
			(start -1.524 0.762)
			(end -1.524 -0.762)
			(stroke
				(width 0.1524)
				(type default)
			)
			(layer "F.SilkS")
		)
		(fp_line
			(start 1.524 0.762)
			(end -1.524 0.762)
			(stroke
				(width 0.1524)
				(type default)
			)
			(layer "F.SilkS")
		)
		(fp_line
			(start -1.524 -0.762)
			(end 1.524 -0.762)
			(stroke
				(width 0.1524)
				(type default)
			)
			(layer "F.SilkS")
		)
		(fp_line
			(start 1.524 -0.762)
			(end 1.524 0.762)
			(stroke
				(width 0.1524)
				(type default)
			)
			(layer "F.SilkS")
		)
		(fp_line
			(start -1.1049 0.724916)
			(end 1.1049 0.724916)
			(stroke
				(width 0.1)
				(type default)
			)
			(layer "F.Fab")
		)
		(fp_line
			(start 1.1049 0.724916)
			(end 1.1049 -0.724916)
			(stroke
				(width 0.1)
				(type default)
			)
			(layer "F.Fab")
		)
		(fp_line
			(start -1.1049 -0.724916)
			(end -1.1049 0.724916)
			(stroke
				(width 0.1)
				(type default)
			)
			(layer "F.Fab")
		)
		(fp_line
			(start 1.1049 -0.724916)
			(end -1.1049 -0.724916)
			(stroke
				(width 0.1)
				(type default)
			)
			(layer "F.Fab")
		)
		(pad "1" smd rect
			(at -0.889 0 90)
			(size 1.016 1.27)
			(layers "F.Cu" "F.Mask" "F.Paste")
			(net "P12V_E1S_0")
		)
		(pad "2" smd rect
			(at 0.889 0 90)
			(size 1.016 1.27)
			(layers "F.Cu" "F.Mask" "F.Paste")
			(net "GND")
		)
	)
	(footprint ""
		(layer "F.Cu")
		(at 422.740074 -151.119586 180)
		(property "Reference" "PC178"
			(at 0 0 180)
			(layer "F.SilkS")
			(hide yes)
			(effects
				(font
					(size 1.27 1.27)
				)
			)
		)
		(property "Value" ""
			(at 0 0 180)
			(layer "F.Fab")
			(effects
				(font
					(size 1.27 1.27)
				)
			)
		)
		(duplicate_pad_numbers_are_jumpers no)
		(fp_line
			(start 0.7874 0.4064)
			(end -0.7874 0.4064)
			(stroke
				(width 0.1524)
				(type default)
			)
			(layer "F.SilkS")
		)
		(fp_line
			(start 0.7874 -0.4064)
			(end 0.7874 0.4064)
			(stroke
				(width 0.1524)
				(type default)
			)
			(layer "F.SilkS")
		)
		(fp_line
			(start -0.7874 0.4064)
			(end -0.7874 -0.4064)
			(stroke
				(width 0.1524)
				(type default)
			)
			(layer "F.SilkS")
		)
		(fp_line
			(start -0.7874 -0.4064)
			(end 0.7874 -0.4064)
			(stroke
				(width 0.1524)
				(type default)
			)
			(layer "F.SilkS")
		)
		(fp_line
			(start 0.67945 0.3048)
			(end 0.120396 0.3048)
			(stroke
				(width 0.1)
				(type default)
			)
			(layer "F.Fab")
		)
		(fp_line
			(start 0.67945 -0.3048)
			(end 0.67945 0.3048)
			(stroke
				(width 0.1)
				(type default)
			)
			(layer "F.Fab")
		)
		(fp_line
			(start 0.12065 -0.2794)
			(end 0.12065 -0.3048)
			(stroke
				(width 0.1)
				(type default)
			)
			(layer "F.Fab")
		)
		(fp_line
			(start 0.12065 -0.3048)
			(end 0.67945 -0.3048)
			(stroke
				(width 0.1)
				(type default)
			)
			(layer "F.Fab")
		)
		(fp_line
			(start 0.120396 0.3048)
			(end 0.120396 0.2794)
			(stroke
				(width 0.1)
				(type default)
			)
			(layer "F.Fab")
		)
		(fp_line
			(start 0.120396 0.2794)
			(end -0.12065 0.2794)
			(stroke
				(width 0.1)
				(type default)
			)
			(layer "F.Fab")
		)
		(fp_line
			(start -0.12065 0.3048)
			(end -0.67945 0.3048)
			(stroke
				(width 0.1)
				(type default)
			)
			(layer "F.Fab")
		)
		(fp_line
			(start -0.12065 0.2794)
			(end -0.12065 0.3048)
			(stroke
				(width 0.1)
				(type default)
			)
			(layer "F.Fab")
		)
		(fp_line
			(start -0.12065 -0.2794)
			(end 0.12065 -0.2794)
			(stroke
				(width 0.1)
				(type default)
			)
			(layer "F.Fab")
		)
		(fp_line
			(start -0.12065 -0.305054)
			(end -0.12065 -0.2794)
			(stroke
				(width 0.1)
				(type default)
			)
			(layer "F.Fab")
		)
		(fp_line
			(start -0.67945 0.3048)
			(end -0.67945 -0.305054)
			(stroke
				(width 0.1)
				(type default)
			)
			(layer "F.Fab")
		)
		(fp_line
			(start -0.67945 -0.305054)
			(end -0.12065 -0.305054)
			(stroke
				(width 0.1)
				(type default)
			)
			(layer "F.Fab")
		)
		(pad "1" smd circle
			(at -0.40005 0 180)
			(size 0 0)
			(layers "F.Cu" "F.Mask" "F.Paste")
			(net "SW_PVCCFA_EHV_CPU0_BOOT1_R")
		)
		(pad "2" smd circle
			(at 0.40005 0 180)
			(size 0 0)
			(layers "F.Cu" "F.Mask" "F.Paste")
			(net "SW_PVCCFA_EHV_CPU0_BOOTR1")
		)
	)
)
